(kicad_pcb
	(version 20260206)
	(generator "pcbnew")
	(generator_version "10.0")
	(general
		(thickness 0.77096)
		(legacy_teardrops no)
	)
	(paper "A4")
	(title_block
		(title "gnss-m2-neo-m9n — M2_NEO-M9N_MODULE.PcbDoc")
		(comment 1 "Time Appliance Project (Time Card) / footprints 37-40 of 40")
	)
	(layers
		(0 "F.Cu" signal "L01-Top Layer")
		(4 "In1.Cu" signal "L02-Inner Layer")
		(6 "In2.Cu" signal "L03-Inner Layer")
		(2 "B.Cu" signal "L04-Bottom Layer")
		(9 "F.Adhes" user "F.Adhesive")
		(11 "B.Adhes" user "B.Adhesive")
		(13 "F.Paste" user "Top Paste")
		(15 "B.Paste" user "Bottom Paste")
		(5 "F.SilkS" user "Top Overlay")
		(7 "B.SilkS" user "Bottom Overlay")
		(1 "F.Mask" user "Top Solder")
		(3 "B.Mask" user "Bottom Solder")
		(17 "Dwgs.User" user "User.Drawings")
		(19 "Cmts.User" user "User.Comments")
		(21 "Eco1.User" user "User.Eco1")
		(23 "Eco2.User" user "User.Eco2")
		(25 "Edge.Cuts" user)
		(27 "Margin" user)
		(31 "F.CrtYd" user "Top Courtyard")
		(29 "B.CrtYd" user "Bottom Courtyard")
		(35 "F.Fab" user "Top Component Outline")
		(33 "B.Fab" user "Bottom Component Outline 2")
	)
	(footprint "Vault:FP-419AB-01-IPC_C"
		(layer "F.Cu")
		(at 143.801105 112.0036 90)
		(property "Reference" "Q2"
			(at 1.722239 -2.679935 360)
			(unlocked yes)
			(layer "F.SilkS")
			(effects
				(font
					(face "Arial")
					(size 0.96012 0.96012)
					(thickness 0.254)
				)
			)
		)
		(property "Value" "2N7002W"
			(at 4.02426 2.937002 90)
			(unlocked yes)
			(layer "F.SilkS")
			(hide yes)
			(effects
				(font
					(size 1.524 1.524)
					(thickness 0.254)
				)
			)
		)
		(sheetname "01-M2_NEO-M9N_MODULE")
		(sheetfile "01-M2_NEO-M9N_MODULE.kicad_sch")
		(duplicate_pad_numbers_are_jumpers no)
		(fp_line
			(start -1.05 -1.25)
			(end 1.05 -1.25)
			(stroke
				(width 0.2)
				(type solid)
			)
			(layer "F.SilkS")
		)
		(fp_line
			(start -1.05 1.25)
			(end 1.05 1.25)
			(stroke
				(width 0.2)
				(type solid)
			)
			(layer "F.SilkS")
		)
		(fp_line
			(start 1.45207 -1.1)
			(end 1.45207 1.1)
			(stroke
				(width 0.2)
				(type solid)
			)
			(layer "F.CrtYd")
		)
		(fp_line
			(start -1.45208 -1.1)
			(end 1.45207 -1.1)
			(stroke
				(width 0.2)
				(type solid)
			)
			(layer "F.CrtYd")
		)
		(fp_line
			(start -1.45208 -1.1)
			(end -1.45208 1.1)
			(stroke
				(width 0.2)
				(type solid)
			)
			(layer "F.CrtYd")
		)
		(fp_line
			(start -1.45208 1.1)
			(end 1.45207 1.1)
			(stroke
				(width 0.2)
				(type solid)
			)
			(layer "F.CrtYd")
		)
		(fp_line
			(start 1.45207 -1.1)
			(end 1.45207 1.1)
			(stroke
				(width 0.2)
				(type solid)
			)
			(layer "F.Fab")
		)
		(fp_line
			(start -1.45208 -1.1)
			(end 1.45207 -1.1)
			(stroke
				(width 0.2)
				(type solid)
			)
			(layer "F.Fab")
		)
		(fp_line
			(start -1.45208 -1.1)
			(end -1.45208 1.1)
			(stroke
				(width 0.2)
				(type solid)
			)
			(layer "F.Fab")
		)
		(fp_line
			(start 0 -0.5)
			(end 0 0.5)
			(stroke
				(width 0.1)
				(type solid)
			)
			(layer "F.Fab")
		)
		(fp_line
			(start -0.5 0)
			(end 0.5 0)
			(stroke
				(width 0.1)
				(type solid)
			)
			(layer "F.Fab")
		)
		(fp_line
			(start -1.45208 1.1)
			(end 1.45207 1.1)
			(stroke
				(width 0.2)
				(type solid)
			)
			(layer "F.Fab")
		)
		(fp_text user "${REFERENCE}"
			(at -0.00001 0.05719 90)
			(unlocked yes)
			(layer "F.Fab")
			(effects
				(font
					(face "Arial")
					(size 0.63 0.63)
					(thickness 0.1)
				)
				(justify left bottom)
			)
		)
		(pad "1" smd rect
			(at -0.7701 -0.65 90)
			(size 1.16396 0.33583)
			(layers "F.Cu" "F.Mask" "F.Paste")
			(net "TP1")
			(solder_mask_margin 0)
			(solder_paste_margin 0)
		)
		(pad "2" smd roundrect
			(at -0.7701 0.65 90)
			(size 1.16396 0.33583)
			(layers "F.Cu" "F.Mask" "F.Paste")
			(roundrect_rratio 0.5)
			(net "GND")
			(solder_mask_margin 0)
			(solder_paste_margin 0)
		)
		(pad "3" smd roundrect
			(at 0.7701 0 90)
			(size 1.16396 0.33583)
			(layers "F.Cu" "F.Mask" "F.Paste")
			(roundrect_rratio 0.5)
			(net "NetLED1_2")
			(solder_mask_margin 0)
			(solder_paste_margin 0)
		)
	)
	(footprint "MyLibrary:TP1MM"
		(layer "F.Cu")
		(at 149.301105 110.6036)
		(property "Reference" "TP9"
			(at -0.783125 1.100005 90)
			(unlocked yes)
			(layer "F.SilkS")
			(effects
				(font
					(face "Arial")
					(size 0.40005 0.40005)
					(thickness 0.1778)
				)
			)
		)
		(property "Value" "1MM"
			(at -2.092783 1.790085 270)
			(unlocked yes)
			(layer "F.SilkS")
			(hide yes)
			(effects
				(font
					(size 0.635 0.635)
					(thickness 0.1778)
				)
			)
		)
		(sheetname "01-M2_NEO-M9N_MODULE")
		(sheetfile "01-M2_NEO-M9N_MODULE.kicad_sch")
		(duplicate_pad_numbers_are_jumpers no)
		(pad "1" smd circle
			(at 0 0)
			(size 1 1)
			(layers "F.Cu" "F.Mask" "F.Paste")
			(net "SCL")
			(solder_paste_margin -100)
			(thermal_bridge_angle 90)
		)
	)
	(footprint "MyLibrary:TP1MM"
		(layer "F.Cu")
		(at 147.901105 110.6036)
		(property "Reference" "TP8"
			(at -0.783125 1.000005 90)
			(unlocked yes)
			(layer "F.SilkS")
			(effects
				(font
					(face "Arial")
					(size 0.40005 0.40005)
					(thickness 0.1778)
				)
			)
		)
		(property "Value" "1MM"
			(at -2.092783 1.790085 270)
			(unlocked yes)
			(layer "F.SilkS")
			(hide yes)
			(effects
				(font
					(size 0.635 0.635)
					(thickness 0.1778)
				)
			)
		)
		(sheetname "01-M2_NEO-M9N_MODULE")
		(sheetfile "01-M2_NEO-M9N_MODULE.kicad_sch")
		(duplicate_pad_numbers_are_jumpers no)
		(pad "1" smd circle
			(at 0 0)
			(size 1 1)
			(layers "F.Cu" "F.Mask" "F.Paste")
			(net "SDA")
			(solder_paste_margin -100)
			(thermal_bridge_angle 90)
		)
	)
	(footprint "MyLibrary:TP1MM"
		(layer "F.Cu")
		(at 150.701105 110.6036 90)
		(property "Reference" "TP11"
			(at -1.92027 1.142197 270)
			(unlocked yes)
			(layer "F.SilkS")
			(effects
				(font
					(size 0.635 0.635)
					(thickness 0.1778)
				)
			)
		)
		(property "Value" "1MM"
			(at -2.092783 1.790085 0)
			(unlocked yes)
			(layer "F.SilkS")
			(hide yes)
			(effects
				(font
					(size 0.635 0.635)
					(thickness 0.1778)
				)
			)
		)
		(sheetname "01-M2_NEO-M9N_MODULE")
		(sheetfile "01-M2_NEO-M9N_MODULE.kicad_sch")
		(duplicate_pad_numbers_are_jumpers no)
		(pad "1" smd circle
			(at 0 0 90)
			(size 1 1)
			(layers "F.Cu" "F.Mask" "F.Paste")
			(net "TX_GPS")
			(solder_paste_margin -100)
			(thermal_bridge_angle 90)
		)
	)
)
